#ISCELL
  pure_quanta quanta_title_block_c *
  *
#CELL
  pure_quanta hole *
  page289_i10
#ISCELL
  logical_power universal_gnd *
  page289_i100
#ISCELL
  logical_power universal_gnd *
  page289_i101
#CELL
  pure_quanta hole *
  page289_i11
#CELL
  pure_quanta hole *
  page289_i12
#CELL
  pure_quanta hole *
  page289_i140
#ISCELL
  logical_power universal_gnd *
  page289_i141
#CELL
  pure_quanta hole *
  page289_i144
#ISCELL
  logical_power universal_gnd *
  page289_i145
#ISCELL
  logical_power universal_gnd *
  page289_i146
#CELL
  pure_quanta hole *
  page289_i147
#CELL
  pure_quanta hole *
  page289_i148
#CELL
  pure_quanta hole *
  page289_i149
#CELL
  pure_quanta hole *
  page289_i150
#ISCELL
  logical_power universal_gnd *
  page289_i151
#ISCELL
  logical_power universal_gnd *
  page289_i152
#ISCELL
  logical_power universal_gnd *
  page289_i153
#CELL
  pure_quanta hole *
  page289_i154
#CELL
  pure_quanta hole *
  page289_i155
#ISCELL
  logical_power universal_gnd *
  page289_i156
#ISCELL
  logical_power universal_gnd *
  page289_i157
#CELL
  pure_quanta hole *
  page289_i158
#CELL
  pure_quanta hole *
  page289_i159
#CELL
  pure_quanta hole *
  page289_i160
#CELL
  pure_quanta hole *
  page289_i161
#ISCELL
  logical_power universal_gnd *
  page289_i162
#ISCELL
  logical_power universal_gnd *
  page289_i163
#ISCELL
  logical_power universal_gnd *
  page289_i164
#CELL
  pure_quanta hole *
  page289_i165
#CELL
  pure_quanta hole *
  page289_i166
#CELL
  pure_quanta hole *
  page289_i167
#CELL
  pure_quanta hole *
  page289_i168
#ISCELL
  logical_power universal_gnd *
  page289_i169
#ISCELL
  logical_power universal_gnd *
  page289_i170
#ISCELL
  logical_power universal_gnd *
  page289_i171
#ISCELL
  logical_power universal_gnd *
  page289_i172
#ISCELL
  logical_power universal_gnd *
  page289_i173
#CELL
  pure_quanta hole *
  page289_i174
#CELL
  pure_quanta hole *
  page289_i175
#ISCELL
  logical_power universal_gnd *
  page289_i176
#ISCELL
  logical_power universal_gnd *
  page289_i177
#CELL
  pure_quanta hole *
  page289_i18
#CELL
  pure_quanta hole *
  page289_i19
#CELL
  pure_quanta hole *
  page289_i190
#ISCELL
  logical_power universal_gnd *
  page289_i191
#CELL
  pure_quanta hole *
  page289_i192
#ISCELL
  logical_power universal_gnd *
  page289_i193
#CELL
  pure_quanta hole *
  page289_i20
#CELL
  pure_quanta gnd_hole *
  page289_i202
#ISCELL
  logical_power universal_gnd *
  page289_i203
#CELL
  pure_quanta gnd_hole *
  page289_i204
#ISCELL
  logical_power universal_gnd *
  page289_i205
#ISCELL
  logical_power universal_gnd *
  page289_i206
#CELL
  pure_quanta gnd_hole *
  page289_i207
#CELL
  pure_quanta hole *
  page289_i21
#CELL
  pure_quanta hole *
  page289_i216
#CELL
  pure_quanta hole *
  page289_i217
#CELL
  pure_quanta hole *
  page289_i218
#CELL
  pure_quanta hole *
  page289_i219
#ISCELL
  logical_power universal_gnd *
  page289_i220
#ISCELL
  logical_power universal_gnd *
  page289_i221
#ISCELL
  logical_power universal_gnd *
  page289_i222
#ISCELL
  logical_power universal_gnd *
  page289_i223
#CELL
  pure_quanta hole *
  page289_i224
#CELL
  pure_quanta hole *
  page289_i225
#CELL
  pure_quanta hole *
  page289_i226
#CELL
  pure_quanta hole *
  page289_i227
#CELL
  pure_quanta hole *
  page289_i228
#CELL
  pure_quanta hole *
  page289_i229
#CELL
  pure_quanta hole *
  page289_i232
#ISCELL
  logical_power universal_gnd *
  page289_i233
#CELL
  pure_quanta conn1_10165288101lf *
  page289_i238
#CELL
  pure_quanta conn1_10165288101lf *
  page289_i239
#ISCELL
  logical_power universal_gnd *
  page289_i243
#ISCELL
  logical_power universal_gnd *
  page289_i244
#ISCELL
  logical_power universal_gnd *
  page289_i245
#CELL
  pure_quanta gnd_hole *
  page289_i247
#CELL
  pure_quanta gnd_hole *
  page289_i248
#CELL
  pure_quanta hole *
  page289_i249
#CELL
  pure_quanta hole *
  page289_i254
#CELL
  pure_quanta hole *
  page289_i54
#ISCELL
  logical_power universal_gnd *
  page289_i55
#CELL
  pure_quanta hole *
  page289_i56
#CELL
  pure_quanta hole *
  page289_i57
#CELL
  pure_quanta hole *
  page289_i58
#ISCELL
  logical_power universal_gnd *
  page289_i59
#CELL
  pure_quanta hole *
  page289_i60
#CELL
  pure_quanta hole *
  page289_i61
#CELL
  pure_quanta hole *
  page289_i63
#CELL
  pure_quanta hole *
  page289_i64
#CELL
  pure_quanta hole *
  page289_i7
#CELL
  pure_quanta hole *
  page289_i72
#CELL
  pure_quanta hole *
  page289_i73
#CELL
  pure_quanta hole *
  page289_i74
#CELL
  pure_quanta hole *
  page289_i75
#CELL
  pure_quanta hole *
  page289_i8
#CELL
  pure_quanta hole *
  page289_i83
#CELL
  pure_quanta hole *
  page289_i87
#CELL
  pure_quanta hole *
  page289_i9
